(kicad_pcb
	(version 20241229)
	(generator "pcbnew")
	(generator_version "9.0")
	(general
		(thickness 1.711)
		(legacy_teardrops no)
	)
	(paper "A4")
	(title_block
		(title "Antmicro Baseboard for Jetson AGX Thor")
		(date "2026-02-18")
		(rev "1.1.0")
		(company "Antmicro Ltd")
		(comment 1 "www.antmicro.com")
		(comment 9 "footprints 1109-1112 of 1170")
	)
	(layers
		(0 "F.Cu" signal)
		(4 "In1.Cu" signal)
		(6 "In2.Cu" signal)
		(8 "In3.Cu" signal)
		(10 "In4.Cu" jumper)
		(12 "In5.Cu" signal)
		(14 "In6.Cu" signal)
		(16 "In7.Cu" signal)
		(18 "In8.Cu" signal)
		(2 "B.Cu" signal)
		(9 "F.Adhes" user "F.Adhesive")
		(11 "B.Adhes" user "B.Adhesive")
		(13 "F.Paste" user)
		(15 "B.Paste" user)
		(5 "F.SilkS" user "F.Silkscreen")
		(7 "B.SilkS" user "B.Silkscreen")
		(1 "F.Mask" user)
		(3 "B.Mask" user)
		(17 "Dwgs.User" user "User.Drawings")
		(19 "Cmts.User" user "User.Comments")
		(21 "Eco1.User" user "User.Eco1")
		(23 "Eco2.User" user "User.Eco2")
		(25 "Edge.Cuts" user)
		(27 "Margin" user)
		(31 "F.CrtYd" user "F.Courtyard")
		(29 "B.CrtYd" user "B.Courtyard")
		(35 "F.Fab" user)
		(33 "B.Fab" user)
	)
	(footprint "antmicro-footprints:SOT-523"
		(layer "B.Cu")
		(at 97.75 60.25 -90)
		(property "Reference" "Q22"
			(at -1 1.25 90)
			(layer "B.SilkS")
			(effects
				(font
					(size 0.7 0.7)
					(thickness 0.15)
				)
				(justify left bottom mirror)
			)
		)
		(property "Value" "DMG1012T-7"
			(at 0.1 -1.824 90)
			(layer "B.Fab")
			(effects
				(font
					(size 0.7 0.7)
					(thickness 0.15)
				)
				(justify left bottom mirror)
			)
		)
		(property "Datasheet" "https://www.diodes.com/assets/Datasheets/ds31783.pdf"
			(at 0 0 90)
			(layer "B.Fab")
			(hide yes)
			(effects
				(font
					(size 1.27 1.27)
					(thickness 0.15)
				)
				(justify mirror)
			)
		)
		(property "Description" "Power MOSFET, N Channel, 20 V, 630 mA, 0.3 ohm, SOT-523, Surface Mount"
			(at 0 0 90)
			(layer "B.Fab")
			(hide yes)
			(effects
				(font
					(size 1.27 1.27)
					(thickness 0.15)
				)
				(justify mirror)
			)
		)
		(property "MPN" "DMG1012T-7"
			(at 0 0 270)
			(unlocked yes)
			(layer "B.Fab")
			(hide yes)
			(effects
				(font
					(size 1 1)
					(thickness 0.15)
				)
				(justify mirror)
			)
		)
		(property "Manufacturer" "Diodes Incorporated"
			(at 0 0 270)
			(unlocked yes)
			(layer "B.Fab")
			(hide yes)
			(effects
				(font
					(size 1 1)
					(thickness 0.15)
				)
				(justify mirror)
			)
		)
		(property "Author" "Antmicro"
			(at 0 0 270)
			(unlocked yes)
			(layer "B.Fab")
			(hide yes)
			(effects
				(font
					(size 1 1)
					(thickness 0.15)
				)
				(justify mirror)
			)
		)
		(property "License" "Apache-2.0"
			(at 0 0 270)
			(unlocked yes)
			(layer "B.Fab")
			(hide yes)
			(effects
				(font
					(size 1 1)
					(thickness 0.15)
				)
				(justify mirror)
			)
		)
		(sheetname "/SoM_Power/")
		(sheetfile "som_power.kicad_sch")
		(attr smd)
		(fp_line
			(start -0.725 0.551)
			(end -0.277 0.551)
			(stroke
				(width 0.15)
				(type solid)
			)
			(layer "B.SilkS")
		)
		(fp_line
			(start -0.277 0.551)
			(end -0.277 0.75)
			(stroke
				(width 0.15)
				(type solid)
			)
			(layer "B.SilkS")
		)
		(fp_line
			(start -0.927 0.351)
			(end -0.725 0.551)
			(stroke
				(width 0.15)
				(type solid)
			)
			(layer "B.SilkS")
		)
		(fp_line
			(start -0.927 0.051)
			(end -0.927 0.351)
			(stroke
				(width 0.15)
				(type solid)
			)
			(layer "B.SilkS")
		)
		(fp_circle
			(center -0.9652 -0.9652)
			(end -0.9152 -0.9652)
			(stroke
				(width 0.15)
				(type solid)
			)
			(fill yes)
			(layer "B.SilkS")
		)
		(fp_line
			(start -1.12 1.16)
			(end 1.1 1.16)
			(stroke
				(width 0.05)
				(type solid)
			)
			(layer "B.CrtYd")
		)
		(fp_line
			(start -1.12 1.16)
			(end -1.12 -1.15)
			(stroke
				(width 0.05)
				(type solid)
			)
			(layer "B.CrtYd")
		)
		(fp_line
			(start 1.1 1.16)
			(end 1.1 -1.15)
			(stroke
				(width 0.05)
				(type solid)
			)
			(layer "B.CrtYd")
		)
		(fp_line
			(start -1.12 -1.15)
			(end 1.1 -1.15)
			(stroke
				(width 0.05)
				(type solid)
			)
			(layer "B.CrtYd")
		)
		(fp_line
			(start -0.652 0.425)
			(end -0.802 0.276)
			(stroke
				(width 0.15)
				(type solid)
			)
			(layer "B.Fab")
		)
		(fp_line
			(start 0.8 0.425)
			(end -0.652 0.425)
			(stroke
				(width 0.15)
				(type solid)
			)
			(layer "B.Fab")
		)
		(fp_line
			(start 0.8 0.425)
			(end 0.8 -0.424)
			(stroke
				(width 0.15)
				(type solid)
			)
			(layer "B.Fab")
		)
		(fp_line
			(start -0.802 0.276)
			(end -0.802 -0.424)
			(stroke
				(width 0.15)
				(type solid)
			)
			(layer "B.Fab")
		)
		(fp_line
			(start 0.8 -0.424)
			(end -0.802 -0.424)
			(stroke
				(width 0.15)
				(type solid)
			)
			(layer "B.Fab")
		)
		(fp_circle
			(center -0.9652 -0.9652)
			(end -0.9144 -0.9652)
			(stroke
				(width 0.15)
				(type solid)
			)
			(fill no)
			(layer "B.Fab")
		)
		(fp_text user "Author: Antmicro"
			(at -1.12 -6.224 90)
			(layer "B.Fab")
			(effects
				(font
					(size 0.7 0.7)
					(thickness 0.15)
				)
				(justify left bottom mirror)
			)
		)
		(fp_text user "License: Apache-2.0"
			(at -1.12 -5.024 90)
			(layer "B.Fab")
			(effects
				(font
					(size 0.7 0.7)
					(thickness 0.15)
				)
				(justify left bottom mirror)
			)
		)
		(fp_text user "${REFERENCE}"
			(at -1.12 -3.824 90)
			(layer "B.Fab")
			(effects
				(font
					(size 0.7 0.7)
					(thickness 0.15)
				)
				(justify left bottom mirror)
			)
		)
		(pad "1" smd rect
			(at -0.5 -0.65 270)
			(size 0.4 0.51)
			(layers "B.Cu" "B.Mask" "B.Paste")
			(net 892 "Net-(Q22-G)")
			(pinfunction "G")
			(pintype "input")
		)
		(pad "2" smd rect
			(at 0.498 -0.65 270)
			(size 0.4 0.51)
			(layers "B.Cu" "B.Mask" "B.Paste")
			(net 1 "GND")
			(pinfunction "S")
			(pintype "passive")
		)
		(pad "3" smd rect
			(at 0 0.652 270)
			(size 0.4 0.51)
			(layers "B.Cu" "B.Mask" "B.Paste")
			(net 524 "Net-(Q22-D)")
			(pinfunction "D")
			(pintype "passive")
		)
	)
	(footprint "antmicro-footprints:R_0402_1005Metric"
		(layer "B.Cu")
		(at 205.4 101.8 180)
		(descr "Resistor SMD 0402")
		(tags "resistor SMD 0402")
		(property "Reference" "R253"
			(at -1.6 0.6 0)
			(layer "B.SilkS")
			(effects
				(font
					(size 0.7 0.7)
					(thickness 0.15)
				)
				(justify left bottom mirror)
			)
		)
		(property "Value" "R_0R_0402"
			(at -1.011843 -1.772046 0)
			(layer "B.Fab")
			(effects
				(font
					(size 0.7 0.7)
					(thickness 0.15)
				)
				(justify left bottom mirror)
			)
		)
		(property "Datasheet" "https://industrial.panasonic.com/cdbs/www-data/pdf/RDA0000/AOA0000C301.pdf"
			(at 0 0 0)
			(layer "B.Fab")
			(hide yes)
			(effects
				(font
					(size 1.27 1.27)
					(thickness 0.15)
				)
				(justify mirror)
			)
		)
		(property "Description" "SMD Chip Resistor, Jumper, 0 ohm, 100 mW, 0402 [1005 Metric], Thick Film, General Purpose"
			(at 0 0 0)
			(layer "B.Fab")
			(hide yes)
			(effects
				(font
					(size 1.27 1.27)
					(thickness 0.15)
				)
				(justify mirror)
			)
		)
		(property "Manufacturer" "Panasonic"
			(at 0 0 0)
			(unlocked yes)
			(layer "B.Fab")
			(hide yes)
			(effects
				(font
					(size 1 1)
					(thickness 0.15)
				)
				(justify mirror)
			)
		)
		(property "MPN" "ERJ2GE0R00X"
			(at 0 0 0)
			(unlocked yes)
			(layer "B.Fab")
			(hide yes)
			(effects
				(font
					(size 1 1)
					(thickness 0.15)
				)
				(justify mirror)
			)
		)
		(property "Val" "0R"
			(at 0 0 0)
			(unlocked yes)
			(layer "B.Fab")
			(hide yes)
			(effects
				(font
					(size 1 1)
					(thickness 0.15)
				)
				(justify mirror)
			)
		)
		(property "License" "Apache-2.0"
			(at 0 0 0)
			(unlocked yes)
			(layer "B.Fab")
			(hide yes)
			(effects
				(font
					(size 1 1)
					(thickness 0.15)
				)
				(justify mirror)
			)
		)
		(property "Author" "Antmicro"
			(at 0 0 0)
			(unlocked yes)
			(layer "B.Fab")
			(hide yes)
			(effects
				(font
					(size 1 1)
					(thickness 0.15)
				)
				(justify mirror)
			)
		)
		(property "Tolerance" "~"
			(at 0 0 0)
			(unlocked yes)
			(layer "B.Fab")
			(hide yes)
			(effects
				(font
					(size 1 1)
					(thickness 0.15)
				)
				(justify mirror)
			)
		)
		(property "Current" "1A"
			(at 0 0 0)
			(unlocked yes)
			(layer "B.Fab")
			(hide yes)
			(effects
				(font
					(size 1 1)
					(thickness 0.15)
				)
				(justify mirror)
			)
		)
		(sheetname "/Recovery USB/")
		(sheetfile "recovery_usb.kicad_sch")
		(attr smd exclude_from_pos_files exclude_from_bom dnp)
		(fp_poly
			(pts
				(xy -0.925 0.47) (xy 0.925 0.47) (xy 0.925 -0.47) (xy -0.925 -0.47)
			)
			(stroke
				(width 0.05)
				(type default)
			)
			(fill no)
			(layer "B.CrtYd")
		)
		(fp_poly
			(pts
				(xy -0.5 0.25) (xy 0.5 0.25) (xy 0.5 -0.25) (xy -0.5 -0.25)
			)
			(stroke
				(width 0.15)
				(type solid)
			)
			(fill no)
			(layer "B.Fab")
		)
		(fp_text user "License: Apache-2.0"
			(at -0.949999 -5.169 0)
			(layer "B.Fab")
			(effects
				(font
					(size 0.7 0.7)
					(thickness 0.15)
				)
				(justify left bottom mirror)
			)
		)
		(fp_text user "${REFERENCE}"
			(at -0.95 -3.168 0)
			(layer "B.Fab")
			(effects
				(font
					(size 0.7 0.7)
					(thickness 0.15)
				)
				(justify left bottom mirror)
			)
		)
		(fp_text user "Author: Antmicro"
			(at -0.95 -4.169 0)
			(layer "B.Fab")
			(effects
				(font
					(size 0.7 0.7)
					(thickness 0.15)
				)
				(justify left bottom mirror)
			)
		)
		(pad "1" smd roundrect
			(at -0.48 0 180)
			(size 0.59 0.64)
			(layers "B.Cu" "B.Mask" "B.Paste")
			(roundrect_rratio 0.25)
			(net 1 "GND")
			(pintype "passive")
		)
		(pad "2" smd roundrect
			(at 0.48 0 180)
			(size 0.59 0.64)
			(layers "B.Cu" "B.Mask" "B.Paste")
			(roundrect_rratio 0.25)
			(net 1011 "/Recovery USB/USBC2_ADDR")
			(pintype "passive")
		)
	)
	(footprint "antmicro-footprints:SOIC-8_3.9x4.9x1.75mm_P1.27mm"
		(layer "B.Cu")
		(at 121 146.999 -90)
		(property "Reference" "U54"
			(at 0 2.85 90)
			(layer "B.SilkS")
			(effects
				(font
					(size 0.7 0.7)
					(thickness 0.15)
				)
				(justify left bottom mirror)
			)
		)
		(property "Value" "AT24CS01_SOIC8"
			(at 0 -3.65 90)
			(layer "B.Fab")
			(effects
				(font
					(size 0.7 0.7)
					(thickness 0.15)
				)
				(justify left bottom mirror)
			)
		)
		(property "Datasheet" "https://ww1.microchip.com/downloads/aemDocuments/documents/MPD/ProductDocuments/DataSheets/20006330A.pdf"
			(at 0 0 90)
			(layer "B.Fab")
			(hide yes)
			(effects
				(font
					(size 1.27 1.27)
					(thickness 0.15)
				)
				(justify mirror)
			)
		)
		(property "Description" "EEPROM, 1 Kbit, 128 x 8bit, Serial I2C (2-Wire), 1 MHz, SOIC-8"
			(at 0 0 90)
			(layer "B.Fab")
			(hide yes)
			(effects
				(font
					(size 1.27 1.27)
					(thickness 0.15)
				)
				(justify mirror)
			)
		)
		(property "Manufacturer" "Microchip Technology"
			(at 0 0 270)
			(unlocked yes)
			(layer "B.Fab")
			(hide yes)
			(effects
				(font
					(size 1 1)
					(thickness 0.15)
				)
				(justify mirror)
			)
		)
		(property "MPN" "AT24CS01-SSHM-B"
			(at 0 0 270)
			(unlocked yes)
			(layer "B.Fab")
			(hide yes)
			(effects
				(font
					(size 1 1)
					(thickness 0.15)
				)
				(justify mirror)
			)
		)
		(property "Author" "Antmicro"
			(at 0 0 270)
			(unlocked yes)
			(layer "B.Fab")
			(hide yes)
			(effects
				(font
					(size 1 1)
					(thickness 0.15)
				)
				(justify mirror)
			)
		)
		(property "License" "Apache-2.0"
			(at 0 0 270)
			(unlocked yes)
			(layer "B.Fab")
			(hide yes)
			(effects
				(font
					(size 1 1)
					(thickness 0.15)
				)
				(justify mirror)
			)
		)
		(sheetname "/Peripherals/")
		(sheetfile "peripherals.kicad_sch")
		(attr smd)
		(fp_line
			(start -1.95 2.452)
			(end 1.95 2.45)
			(stroke
				(width 0.15)
				(type solid)
			)
			(layer "B.SilkS")
		)
		(fp_line
			(start -1.95 -2.45)
			(end 1.95 -2.45)
			(stroke
				(width 0.15)
				(type solid)
			)
			(layer "B.SilkS")
		)
		(fp_circle
			(center -2.4 2.45)
			(end -2.35 2.4)
			(stroke
				(width 0.15)
				(type solid)
			)
			(fill yes)
			(layer "B.SilkS")
		)
		(fp_rect
			(start -3.625 2.7)
			(end 3.625 -2.7)
			(stroke
				(width 0.05)
				(type solid)
			)
			(fill no)
			(layer "B.CrtYd")
		)
		(fp_line
			(start -0.683 2.452)
			(end 1.949 2.452)
			(stroke
				(width 0.15)
				(type solid)
			)
			(layer "B.Fab")
		)
		(fp_line
			(start 1.949 2.452)
			(end 1.949 -2.45)
			(stroke
				(width 0.15)
				(type solid)
			)
			(layer "B.Fab")
		)
		(fp_line
			(start -1.95 1.18)
			(end -0.683 2.452)
			(stroke
				(width 0.15)
				(type solid)
			)
			(layer "B.Fab")
		)
		(fp_line
			(start -1.95 -2.45)
			(end -1.95 1.18)
			(stroke
				(width 0.15)
				(type solid)
			)
			(layer "B.Fab")
		)
		(fp_line
			(start 1.949 -2.45)
			(end -1.95 -2.45)
			(stroke
				(width 0.15)
				(type solid)
			)
			(layer "B.Fab")
		)
		(fp_text user "License: Apache-2.0"
			(at -3.476 -5.099 90)
			(layer "B.Fab")
			(effects
				(font
					(size 0.7 0.7)
					(thickness 0.15)
				)
				(justify left bottom mirror)
			)
		)
		(fp_text user "Author: Antmicro"
			(at -3.476 -6.099 90)
			(layer "B.Fab")
			(effects
				(font
					(size 0.7 0.7)
					(thickness 0.15)
				)
				(justify left bottom mirror)
			)
		)
		(fp_text user "${REFERENCE}"
			(at -3.476 -7.099 90)
			(layer "B.Fab")
			(effects
				(font
					(size 0.7 0.7)
					(thickness 0.15)
				)
				(justify left bottom mirror)
			)
		)
		(pad "1" smd roundrect
			(at -2.714 1.905 180)
			(size 0.65 1.525)
			(layers "B.Cu" "B.Mask" "B.Paste")
			(roundrect_rratio 0.25)
			(net 1 "GND")
			(pinfunction "A0")
			(pintype "input")
		)
		(pad "2" smd roundrect
			(at -2.714 0.635 180)
			(size 0.65 1.525)
			(layers "B.Cu" "B.Mask" "B.Paste")
			(roundrect_rratio 0.25)
			(net 1 "GND")
			(pinfunction "A1")
			(pintype "input")
		)
		(pad "3" smd roundrect
			(at -2.714 -0.632 180)
			(size 0.65 1.525)
			(layers "B.Cu" "B.Mask" "B.Paste")
			(roundrect_rratio 0.25)
			(net 1 "GND")
			(pinfunction "A2")
			(pintype "input")
		)
		(pad "4" smd roundrect
			(at -2.714 -1.902 180)
			(size 0.65 1.525)
			(layers "B.Cu" "B.Mask" "B.Paste")
			(roundrect_rratio 0.25)
			(net 1 "GND")
			(pinfunction "GND")
			(pintype "power_in")
		)
		(pad "5" smd roundrect
			(at 2.712 -1.902 180)
			(size 0.65 1.525)
			(layers "B.Cu" "B.Mask" "B.Paste")
			(roundrect_rratio 0.25)
			(net 853 "/I2C_{SYS}.SCL")
			(pinfunction "SDA")
			(pintype "bidirectional")
		)
		(pad "6" smd roundrect
			(at 2.712 -0.632 180)
			(size 0.65 1.525)
			(layers "B.Cu" "B.Mask" "B.Paste")
			(roundrect_rratio 0.25)
			(net 850 "/I2C_{SYS}.SDA")
			(pinfunction "SCL")
			(pintype "input")
		)
		(pad "7" smd roundrect
			(at 2.712 0.635 180)
			(size 0.65 1.525)
			(layers "B.Cu" "B.Mask" "B.Paste")
			(roundrect_rratio 0.25)
			(net 1 "GND")
			(pinfunction "WP")
			(pintype "input")
		)
		(pad "8" smd roundrect
			(at 2.712 1.905 180)
			(size 0.65 1.525)
			(layers "B.Cu" "B.Mask" "B.Paste")
			(roundrect_rratio 0.25)
			(net 4 "+3V3_AON")
			(pinfunction "VCC")
			(pintype "power_in")
		)
	)
	(footprint "antmicro-footprints:R_0402_1005Metric"
		(layer "B.Cu")
		(at 212.8 89.8)
		(descr "Resistor SMD 0402")
		(tags "resistor SMD 0402")
		(property "Reference" "R135"
			(at -3.9 -0.3 0)
			(layer "B.SilkS")
			(effects
				(font
					(size 0.7 0.7)
					(thickness 0.15)
				)
				(justify right top mirror)
			)
		)
		(property "Value" "R_1k_0402"
			(at -1.011843 -1.772046 0)
			(layer "B.Fab")
			(effects
				(font
					(size 0.7 0.7)
					(thickness 0.15)
				)
				(justify right top mirror)
			)
		)
		(property "Datasheet" "https://www.bourns.com/docs/product-datasheets/cr.pdf"
			(at 0 0 0)
			(layer "B.Fab")
			(hide yes)
			(effects
				(font
					(size 1.27 1.27)
					(thickness 0.15)
				)
				(justify mirror)
			)
		)
		(property "Description" "SMD Chip Resistor, 1 kohm, ± 1%, 63 mW, 0402 [1005 Metric], Thick Film, General Purpose"
			(at 0 0 0)
			(layer "B.Fab")
			(hide yes)
			(effects
				(font
					(size 1.27 1.27)
					(thickness 0.15)
				)
				(justify mirror)
			)
		)
		(property "Manufacturer" "Bourns"
			(at 0 0 180)
			(unlocked yes)
			(layer "B.Fab")
			(hide yes)
			(effects
				(font
					(size 1 1)
					(thickness 0.15)
				)
				(justify mirror)
			)
		)
		(property "MPN" "CR0402-FX-1001GLF"
			(at 0 0 180)
			(unlocked yes)
			(layer "B.Fab")
			(hide yes)
			(effects
				(font
					(size 1 1)
					(thickness 0.15)
				)
				(justify mirror)
			)
		)
		(property "Val" "1k"
			(at 0 0 180)
			(unlocked yes)
			(layer "B.Fab")
			(hide yes)
			(effects
				(font
					(size 1 1)
					(thickness 0.15)
				)
				(justify mirror)
			)
		)
		(property "License" "Apache-2.0"
			(at 0 0 180)
			(unlocked yes)
			(layer "B.Fab")
			(hide yes)
			(effects
				(font
					(size 1 1)
					(thickness 0.15)
				)
				(justify mirror)
			)
		)
		(property "Author" "Antmicro"
			(at 0 0 180)
			(unlocked yes)
			(layer "B.Fab")
			(hide yes)
			(effects
				(font
					(size 1 1)
					(thickness 0.15)
				)
				(justify mirror)
			)
		)
		(property "Tolerance" "1%"
			(at 0 0 180)
			(unlocked yes)
			(layer "B.Fab")
			(hide yes)
			(effects
				(font
					(size 1 1)
					(thickness 0.15)
				)
				(justify mirror)
			)
		)
		(sheetname "/USB DP Alt mode/")
		(sheetfile "usb_dp.kicad_sch")
		(attr smd exclude_from_pos_files exclude_from_bom dnp)
		(fp_poly
			(pts
				(xy -0.925 0.47) (xy 0.925 0.47) (xy 0.925 -0.47) (xy -0.925 -0.47)
			)
			(stroke
				(width 0.05)
				(type default)
			)
			(fill no)
			(layer "B.CrtYd")
		)
		(fp_poly
			(pts
				(xy -0.5 0.25) (xy 0.5 0.25) (xy 0.5 -0.25) (xy -0.5 -0.25)
			)
			(stroke
				(width 0.15)
				(type solid)
			)
			(fill no)
			(layer "B.Fab")
		)
		(fp_text user "License: Apache-2.0"
			(at -0.949999 -5.169 0)
			(layer "B.Fab")
			(effects
				(font
					(size 0.7 0.7)
					(thickness 0.15)
				)
				(justify right top mirror)
			)
		)
		(fp_text user "${REFERENCE}"
			(at -0.95 -3.168 0)
			(layer "B.Fab")
			(effects
				(font
					(size 0.7 0.7)
					(thickness 0.15)
				)
				(justify right top mirror)
			)
		)
		(fp_text user "Author: Antmicro"
			(at -0.95 -4.169 0)
			(layer "B.Fab")
			(effects
				(font
					(size 0.7 0.7)
					(thickness 0.15)
				)
				(justify right top mirror)
			)
		)
		(pad "1" smd roundrect
			(at -0.48 0)
			(size 0.59 0.64)
			(layers "B.Cu" "B.Mask" "B.Paste")
			(roundrect_rratio 0.25)
			(net 966 "/USB DP Alt mode/USBC1_DPEQ0")
			(pintype "passive")
		)
		(pad "2" smd roundrect
			(at 0.48 0)
			(size 0.59 0.64)
			(layers "B.Cu" "B.Mask" "B.Paste")
			(roundrect_rratio 0.25)
			(net 1 "GND")
			(pintype "passive")
		)
	)
)
